# SCM (Grand Teton) — schematic netlist excerpt (pin names and nets, part order shuffled) for the footprints in the layout excerpt that follows; sources: Cadence DE-HDL packaged netlist, KiCad conversion of 12092022_DA0F0TMDCD0_F0T_Management_Board_D_brd_V3_OCP.brd

PR275  Q_RES  0 5% EMPTY  pkg 0402LF  page 55 : A = P5V_AUX ; B = PVCC1_AUX
R820  Q_RES  100K 1% EMPTY  pkg 0402LF  page 12 : A = SMB_BMC_MM14_R_SDA ; B = GND

(kicad_pcb
	(version 20260206)
	(generator "pcbnew")
	(generator_version "10.0")
	(general
		(thickness 1.6)
		(legacy_teardrops no)
	)
	(paper "A4")
	(title_block
		(title "12092022_DA0F0TMDCD0_F0T_Management_Board_D_brd_V3_OCP.brd")
		(comment 1 "Grand Teton / footprints 165-166 of 1440")
	)
	(layers
		(0 "F.Cu" signal "TOP")
		(4 "In1.Cu" signal "GND")
		(6 "In2.Cu" signal "IN1")
		(8 "In3.Cu" signal "GND1")
		(10 "In4.Cu" signal "IN2")
		(12 "In5.Cu" signal "VCC")
		(14 "In6.Cu" signal "VCC1")
		(16 "In7.Cu" signal "IN3")
		(18 "In8.Cu" signal "GND2")
		(20 "In9.Cu" signal "IN4")
		(22 "In10.Cu" signal "GND3")
		(2 "B.Cu" signal "BOTTOM")
		(9 "F.Adhes" user "F.Adhesive")
		(11 "B.Adhes" user "B.Adhesive")
		(13 "F.Paste" user "Package Geometry/Pastemask Top")
		(15 "B.Paste" user "Package Geometry/Pastemask Bottom")
		(5 "F.SilkS" user "Ref Des/Silkscreen Top")
		(7 "B.SilkS" user "Ref Des/Silkscreen Bottom")
		(1 "F.Mask" user "Board Geometry/Soldermask Top")
		(3 "B.Mask" user "Board Geometry/Soldermask Bottom")
		(17 "Dwgs.User" user "User.Drawings")
		(19 "Cmts.User" user "User.Comments")
		(21 "Eco1.User" user "User.Eco1")
		(23 "Eco2.User" user "User.Eco2")
		(25 "Edge.Cuts" user "Board Geometry/Outline")
		(27 "Margin" user)
		(31 "F.CrtYd" user "Package Geometry/Place Bound Top")
		(29 "B.CrtYd" user "Package Geometry/Place Bound Bottom")
		(35 "F.Fab" user "Ref Des/Assembly Top")
		(33 "B.Fab" user "Ref Des/Assembly Bottom")
	)
	(footprint ""
		(layer "F.Cu")
		(at 85.7504 -70.4596 -90)
		(property "Reference" "PR275"
			(at 0 0 270)
			(layer "F.SilkS")
			(hide yes)
			(effects
				(font
					(size 1.27 1.27)
				)
			)
		)
		(property "Value" ""
			(at 0 0 270)
			(layer "F.Fab")
			(effects
				(font
					(size 1.27 1.27)
				)
			)
		)
		(duplicate_pad_numbers_are_jumpers no)
		(fp_line
			(start -0.7874 0.4064)
			(end -0.7874 -0.4064)
			(stroke
				(width 0.1524)
				(type default)
			)
			(layer "F.SilkS")
		)
		(fp_line
			(start 0.7874 0.4064)
			(end -0.7874 0.4064)
			(stroke
				(width 0.1524)
				(type default)
			)
			(layer "F.SilkS")
		)
		(fp_line
			(start -0.7874 -0.4064)
			(end 0.7874 -0.4064)
			(stroke
				(width 0.1524)
				(type default)
			)
			(layer "F.SilkS")
		)
		(fp_line
			(start 0.7874 -0.4064)
			(end 0.7874 0.4064)
			(stroke
				(width 0.1524)
				(type default)
			)
			(layer "F.SilkS")
		)
		(fp_line
			(start -0.67945 0.3048)
			(end -0.67945 -0.305054)
			(stroke
				(width 0.1)
				(type default)
			)
			(layer "F.Fab")
		)
		(fp_line
			(start -0.12065 0.3048)
			(end -0.67945 0.3048)
			(stroke
				(width 0.1)
				(type default)
			)
			(layer "F.Fab")
		)
		(fp_line
			(start 0.120396 0.3048)
			(end 0.120396 0.2794)
			(stroke
				(width 0.1)
				(type default)
			)
			(layer "F.Fab")
		)
		(fp_line
			(start 0.67945 0.3048)
			(end 0.120396 0.3048)
			(stroke
				(width 0.1)
				(type default)
			)
			(layer "F.Fab")
		)
		(fp_line
			(start -0.12065 0.2794)
			(end -0.12065 0.3048)
			(stroke
				(width 0.1)
				(type default)
			)
			(layer "F.Fab")
		)
		(fp_line
			(start 0.120396 0.2794)
			(end -0.12065 0.2794)
			(stroke
				(width 0.1)
				(type default)
			)
			(layer "F.Fab")
		)
		(fp_line
			(start -0.12065 -0.2794)
			(end 0.12065 -0.2794)
			(stroke
				(width 0.1)
				(type default)
			)
			(layer "F.Fab")
		)
		(fp_line
			(start 0.12065 -0.2794)
			(end 0.12065 -0.3048)
			(stroke
				(width 0.1)
				(type default)
			)
			(layer "F.Fab")
		)
		(fp_line
			(start 0.12065 -0.3048)
			(end 0.67945 -0.3048)
			(stroke
				(width 0.1)
				(type default)
			)
			(layer "F.Fab")
		)
		(fp_line
			(start 0.67945 -0.3048)
			(end 0.67945 0.3048)
			(stroke
				(width 0.1)
				(type default)
			)
			(layer "F.Fab")
		)
		(fp_line
			(start -0.67945 -0.305054)
			(end -0.12065 -0.305054)
			(stroke
				(width 0.1)
				(type default)
			)
			(layer "F.Fab")
		)
		(fp_line
			(start -0.12065 -0.305054)
			(end -0.12065 -0.2794)
			(stroke
				(width 0.1)
				(type default)
			)
			(layer "F.Fab")
		)
		(pad "1" smd circle
			(at -0.40005 0 270)
			(size 0 0)
			(layers "F.Cu" "F.Mask" "F.Paste")
			(net "P5V_AUX")
		)
		(pad "2" smd circle
			(at 0.40005 0 270)
			(size 0 0)
			(layers "F.Cu" "F.Mask" "F.Paste")
			(net "PVCC1_AUX")
		)
	)
	(footprint ""
		(layer "F.Cu")
		(at 39.932864 -45.384466 180)
		(property "Reference" "R820"
			(at 0 0 180)
			(layer "F.SilkS")
			(hide yes)
			(effects
				(font
					(size 1.27 1.27)
				)
			)
		)
		(property "Value" ""
			(at 0 0 180)
			(layer "F.Fab")
			(effects
				(font
					(size 1.27 1.27)
				)
			)
		)
		(duplicate_pad_numbers_are_jumpers no)
		(fp_line
			(start 0.7874 0.4064)
			(end -0.7874 0.4064)
			(stroke
				(width 0.1524)
				(type default)
			)
			(layer "F.SilkS")
		)
		(fp_line
			(start 0.7874 -0.4064)
			(end 0.7874 0.4064)
			(stroke
				(width 0.1524)
				(type default)
			)
			(layer "F.SilkS")
		)
		(fp_line
			(start -0.7874 0.4064)
			(end -0.7874 -0.4064)
			(stroke
				(width 0.1524)
				(type default)
			)
			(layer "F.SilkS")
		)
		(fp_line
			(start -0.7874 -0.4064)
			(end 0.7874 -0.4064)
			(stroke
				(width 0.1524)
				(type default)
			)
			(layer "F.SilkS")
		)
		(fp_line
			(start 0.67945 0.3048)
			(end 0.120396 0.3048)
			(stroke
				(width 0.1)
				(type default)
			)
			(layer "F.Fab")
		)
		(fp_line
			(start 0.67945 -0.3048)
			(end 0.67945 0.3048)
			(stroke
				(width 0.1)
				(type default)
			)
			(layer "F.Fab")
		)
		(fp_line
			(start 0.12065 -0.2794)
			(end 0.12065 -0.3048)
			(stroke
				(width 0.1)
				(type default)
			)
			(layer "F.Fab")
		)
		(fp_line
			(start 0.12065 -0.3048)
			(end 0.67945 -0.3048)
			(stroke
				(width 0.1)
				(type default)
			)
			(layer "F.Fab")
		)
		(fp_line
			(start 0.120396 0.3048)
			(end 0.120396 0.2794)
			(stroke
				(width 0.1)
				(type default)
			)
			(layer "F.Fab")
		)
		(fp_line
			(start 0.120396 0.2794)
			(end -0.12065 0.2794)
			(stroke
				(width 0.1)
				(type default)
			)
			(layer "F.Fab")
		)
		(fp_line
			(start -0.12065 0.3048)
			(end -0.67945 0.3048)
			(stroke
				(width 0.1)
				(type default)
			)
			(layer "F.Fab")
		)
		(fp_line
			(start -0.12065 0.2794)
			(end -0.12065 0.3048)
			(stroke
				(width 0.1)
				(type default)
			)
			(layer "F.Fab")
		)
		(fp_line
			(start -0.12065 -0.2794)
			(end 0.12065 -0.2794)
			(stroke
				(width 0.1)
				(type default)
			)
			(layer "F.Fab")
		)
		(fp_line
			(start -0.12065 -0.305054)
			(end -0.12065 -0.2794)
			(stroke
				(width 0.1)
				(type default)
			)
			(layer "F.Fab")
		)
		(fp_line
			(start -0.67945 0.3048)
			(end -0.67945 -0.305054)
			(stroke
				(width 0.1)
				(type default)
			)
			(layer "F.Fab")
		)
		(fp_line
			(start -0.67945 -0.305054)
			(end -0.12065 -0.305054)
			(stroke
				(width 0.1)
				(type default)
			)
			(layer "F.Fab")
		)
		(pad "1" smd circle
			(at -0.40005 0 180)
			(size 0 0)
			(layers "F.Cu" "F.Mask" "F.Paste")
			(net "SMB_BMC_MM14_R_SDA")
		)
		(pad "2" smd circle
			(at 0.40005 0 180)
			(size 0 0)
			(layers "F.Cu" "F.Mask" "F.Paste")
			(net "GND")
		)
	)
)
